(kicad_pcb
	(version 20260206)
	(generator "pcbnew")
	(generator_version "10.0")
	(general
		(thickness 1.6)
		(legacy_teardrops no)
	)
	(paper "A4")
	(title_block
		(title "Wiwynn_Tioga_Pass_MB.brd")
		(comment 1 "Tioga Pass / footprints 2351-2357 of 4770")
	)
	(layers
		(0 "F.Cu" signal "TOP")
		(4 "In1.Cu" signal "L2GND")
		(6 "In2.Cu" signal "L3")
		(8 "In3.Cu" signal "L4GND")
		(10 "In4.Cu" signal "L5")
		(12 "In5.Cu" signal "L6GND")
		(14 "In6.Cu" signal "L7VCC")
		(16 "In7.Cu" signal "L8VCC")
		(18 "In8.Cu" signal "L9GND")
		(20 "In9.Cu" signal "L10")
		(22 "In10.Cu" signal "L11GND")
		(24 "In11.Cu" signal "L12")
		(26 "In12.Cu" signal "L13GND")
		(2 "B.Cu" signal "BOTTOM")
		(9 "F.Adhes" user "F.Adhesive")
		(11 "B.Adhes" user "B.Adhesive")
		(13 "F.Paste" user "Package Geometry/Pastemask Top")
		(15 "B.Paste" user "Package Geometry/Pastemask Bottom")
		(5 "F.SilkS" user "Ref Des/Silkscreen Top")
		(7 "B.SilkS" user "Ref Des/Silkscreen Bottom")
		(1 "F.Mask" user "Board Geometry/Soldermask Top")
		(3 "B.Mask" user "Board Geometry/Soldermask Bottom")
		(17 "Dwgs.User" user "User.Drawings")
		(19 "Cmts.User" user "User.Comments")
		(21 "Eco1.User" user "User.Eco1")
		(23 "Eco2.User" user "User.Eco2")
		(25 "Edge.Cuts" user "Board Geometry/Outline")
		(27 "Margin" user)
		(31 "F.CrtYd" user "Package Geometry/Place Bound Top")
		(29 "B.CrtYd" user "Package Geometry/Place Bound Bottom")
		(35 "F.Fab" user "Ref Des/Assembly Top")
		(33 "B.Fab" user "Ref Des/Assembly Bottom")
	)
	(footprint ""
		(layer "B.Cu")
		(at 194.691 -135.763)
		(property "Reference" "R6L16"
			(at 0 0 0)
			(layer "B.SilkS")
			(hide yes)
			(effects
				(font
					(size 1.27 1.27)
				)
				(justify mirror)
			)
		)
		(property "Value" ""
			(at 0 0 0)
			(layer "B.Fab")
			(effects
				(font
					(size 1.27 1.27)
				)
				(justify mirror)
			)
		)
		(duplicate_pad_numbers_are_jumpers no)
		(fp_poly
			(pts
				(xy 0.2794 -0.1016) (xy -0.2794 -0.1016) (xy -0.2794 0.9906) (xy 0.2794 0.9906)
			)
			(stroke
				(width 0)
				(type default)
			)
			(fill no)
			(layer "B.CrtYd")
		)
		(fp_line
			(start -0.2794 -0.1016)
			(end 0.2794 -0.1016)
			(stroke
				(width 0.1)
				(type default)
			)
			(layer "B.Fab")
		)
		(fp_line
			(start -0.2794 0.9906)
			(end -0.2794 -0.1016)
			(stroke
				(width 0.1)
				(type default)
			)
			(layer "B.Fab")
		)
		(fp_line
			(start 0.2794 -0.1016)
			(end 0.2794 0.9906)
			(stroke
				(width 0.1)
				(type default)
			)
			(layer "B.Fab")
		)
		(fp_line
			(start 0.2794 0.9906)
			(end -0.2794 0.9906)
			(stroke
				(width 0.1)
				(type default)
			)
			(layer "B.Fab")
		)
		(pad "1" smd rect
			(at 0 0 180)
			(size 0.508 0.508)
			(layers "B.Cu" "B.Mask" "B.Paste")
			(net "M_D_VREF")
		)
		(pad "2" smd rect
			(at 0 0.889 180)
			(size 0.508 0.508)
			(layers "B.Cu" "B.Mask" "B.Paste")
			(net "GND")
		)
		(zone
			(layer "B.Cu")
			(hatch none 0.5)
			(connect_pads
				(clearance 0)
			)
			(min_thickness 0.25)
			(keepout
				(tracks allowed)
				(vias not_allowed)
				(pads allowed)
				(copperpour not_allowed)
				(footprints allowed)
			)
			(placement
				(enabled no)
				(sheetname "")
			)
			(fill
				(thermal_gap 0.5)
				(thermal_bridge_width 0.5)
				(island_removal_mode 0)
			)
			(polygon
				(pts
					(xy 194.945 -135.509) (xy 194.437 -135.509) (xy 194.437 -135.128) (xy 194.945 -135.128)
				)
			)
		)
		(zone
			(layer "B.Cu")
			(hatch none 0.5)
			(connect_pads
				(clearance 0)
			)
			(min_thickness 0.25)
			(keepout
				(tracks not_allowed)
				(vias allowed)
				(pads allowed)
				(copperpour not_allowed)
				(footprints allowed)
			)
			(placement
				(enabled no)
				(sheetname "")
			)
			(fill
				(thermal_gap 0.5)
				(thermal_bridge_width 0.5)
				(island_removal_mode 0)
			)
			(polygon
				(pts
					(xy 194.945 -135.128) (xy 194.437 -135.128) (xy 194.437 -135.509) (xy 194.945 -135.509)
				)
			)
		)
	)
	(footprint ""
		(layer "B.Cu")
		(at 353.654614 -123.780042 -90)
		(property "Reference" "R775"
			(at 0.8382 -0.67818 270)
			(unlocked yes)
			(layer "B.SilkS")
			(effects
				(font
					(size 0.4064 0.254)
					(thickness 0.1524)
				)
				(justify left mirror)
			)
		)
		(property "Value" ""
			(at 0 0 90)
			(layer "B.Fab")
			(effects
				(font
					(size 1.27 1.27)
				)
				(justify mirror)
			)
		)
		(duplicate_pad_numbers_are_jumpers no)
		(fp_poly
			(pts
				(xy 0.2794 -0.1016) (xy -0.2794 -0.1016) (xy -0.2794 0.9906) (xy 0.2794 0.9906)
			)
			(stroke
				(width 0)
				(type default)
			)
			(fill no)
			(layer "B.CrtYd")
		)
		(fp_line
			(start -0.2794 0.9906)
			(end -0.2794 -0.1016)
			(stroke
				(width 0.1)
				(type default)
			)
			(layer "B.Fab")
		)
		(fp_line
			(start 0.2794 0.9906)
			(end -0.2794 0.9906)
			(stroke
				(width 0.1)
				(type default)
			)
			(layer "B.Fab")
		)
		(fp_line
			(start -0.2794 -0.1016)
			(end 0.2794 -0.1016)
			(stroke
				(width 0.1)
				(type default)
			)
			(layer "B.Fab")
		)
		(fp_line
			(start 0.2794 -0.1016)
			(end 0.2794 0.9906)
			(stroke
				(width 0.1)
				(type default)
			)
			(layer "B.Fab")
		)
		(pad "1" smd rect
			(at 0 0 90)
			(size 0.508 0.508)
			(layers "B.Cu" "B.Mask" "B.Paste")
			(net "P3E_CPU0_PE1_PCH_RXN<12>")
		)
		(pad "2" smd rect
			(at 0 0.889 90)
			(size 0.508 0.508)
			(layers "B.Cu" "B.Mask" "B.Paste")
			(net "P3E_CPU0_PE1_PCH_CON_RXN<12>")
		)
		(zone
			(layer "B.Cu")
			(hatch none 0.5)
			(connect_pads
				(clearance 0)
			)
			(min_thickness 0.25)
			(keepout
				(tracks not_allowed)
				(vias allowed)
				(pads allowed)
				(copperpour not_allowed)
				(footprints allowed)
			)
			(placement
				(enabled no)
				(sheetname "")
			)
			(fill
				(thermal_gap 0.5)
				(thermal_bridge_width 0.5)
				(island_removal_mode 0)
			)
			(polygon
				(pts
					(xy 353.019614 -123.526042) (xy 353.019614 -124.034042) (xy 353.400614 -124.034042) (xy 353.400614 -123.526042)
				)
			)
		)
		(zone
			(layer "B.Cu")
			(hatch none 0.5)
			(connect_pads
				(clearance 0)
			)
			(min_thickness 0.25)
			(keepout
				(tracks allowed)
				(vias not_allowed)
				(pads allowed)
				(copperpour not_allowed)
				(footprints allowed)
			)
			(placement
				(enabled no)
				(sheetname "")
			)
			(fill
				(thermal_gap 0.5)
				(thermal_bridge_width 0.5)
				(island_removal_mode 0)
			)
			(polygon
				(pts
					(xy 353.400614 -123.526042) (xy 353.400614 -124.034042) (xy 353.019614 -124.034042) (xy 353.019614 -123.526042)
				)
			)
		)
	)
	(footprint ""
		(layer "B.Cu")
		(at 388.892542 -12.473432)
		(property "Reference" "U32W2"
			(at 0 0 0)
			(layer "B.SilkS")
			(hide yes)
			(effects
				(font
					(size 1.27 1.27)
				)
				(justify mirror)
			)
		)
		(property "Value" "*"
			(at 0.1143 -9.3091 0)
			(unlocked yes)
			(layer "B.Fab")
			(hide yes)
			(effects
				(font
					(size 1.27 1.016)
					(thickness 0.1524)
				)
				(justify mirror)
			)
		)
		(property "Device Type" "TCA9517DGKR-GP_DISCRET-G8-TCA9A"
			(at 0.1143 -10.9093 0)
			(unlocked yes)
			(layer "B.Fab")
			(hide yes)
			(effects
				(font
					(size 1.27 1.016)
					(thickness 0.1524)
				)
				(justify mirror)
			)
		)
		(duplicate_pad_numbers_are_jumpers no)
		(fp_line
			(start -1.0795 -1.016)
			(end 1.9558 -1.016)
			(stroke
				(width 0.1524)
				(type default)
			)
			(layer "B.SilkS")
		)
		(fp_line
			(start -1.0795 1.016)
			(end -1.0795 -1.016)
			(stroke
				(width 0.1524)
				(type default)
			)
			(layer "B.SilkS")
		)
		(fp_line
			(start 1.4478 -0.0381)
			(end 1.9558 0.4699)
			(stroke
				(width 0.1524)
				(type default)
			)
			(layer "B.SilkS")
		)
		(fp_line
			(start 1.778 1.0922)
			(end 1.778 3.048)
			(stroke
				(width 0.508)
				(type default)
			)
			(layer "B.SilkS")
		)
		(fp_line
			(start 1.9558 -1.016)
			(end 1.9558 1.016)
			(stroke
				(width 0.1524)
				(type default)
			)
			(layer "B.SilkS")
		)
		(fp_line
			(start 1.9558 -0.5461)
			(end 1.4478 -0.0381)
			(stroke
				(width 0.1524)
				(type default)
			)
			(layer "B.SilkS")
		)
		(fp_line
			(start 1.9558 1.016)
			(end -1.0795 1.016)
			(stroke
				(width 0.1524)
				(type default)
			)
			(layer "B.SilkS")
		)
		(fp_poly
			(pts
				(xy 1.1557 -1.016) (xy 1.1557 1.016) (xy -1.1557 1.016) (xy -1.1557 -1.016)
			)
			(stroke
				(width 0)
				(type default)
			)
			(fill yes)
			(layer "B.SilkS")
		)
		(fp_rect
			(start 1.4986 2.4511)
			(end -1.4986 -2.4511)
			(stroke
				(width 0)
				(type default)
			)
			(fill no)
			(layer "B.CrtYd")
		)
		(fp_poly
			(pts
				(xy 2.032 3.302) (xy 2.032 -3.302) (xy -2.032 -3.302) (xy -2.032 -2.1209) (xy -1.4986 -2.1209) (xy -1.4986 -2.4511)
				(xy 1.4986 -2.4511) (xy 1.4986 2.4511) (xy -1.4986 2.4511) (xy -1.4986 -2.1082) (xy -2.032 -2.1082)
				(xy -2.032 3.302)
			)
			(stroke
				(width 0)
				(type default)
			)
			(fill no)
			(layer "B.CrtYd")
		)
		(fp_rect
			(start 2.032 3.302)
			(end -2.032 -3.302)
			(stroke
				(width 0)
				(type default)
			)
			(fill no)
			(layer "B.Fab")
		)
		(pad "1" smd rect
			(at 0.97536 2.05486 180)
			(size 0.3556 1.524)
			(layers "B.Cu" "B.Mask" "B.Paste")
			(net "P1V8_M2")
		)
		(pad "2" smd rect
			(at 0.32512 2.05486 180)
			(size 0.3556 1.524)
			(layers "B.Cu" "B.Mask" "B.Paste")
			(net "SMB_M2_ALT_R_N")
		)
		(pad "3" smd rect
			(at -0.32512 2.05486 180)
			(size 0.3556 1.524)
			(layers "B.Cu" "B.Mask" "B.Paste")
			(net "Net_6507")
		)
		(pad "4" smd rect
			(at -0.97536 2.05486 180)
			(size 0.3556 1.524)
			(layers "B.Cu" "B.Mask" "B.Paste")
			(net "GND")
		)
		(pad "5" smd rect
			(at -0.97536 -2.05486 180)
			(size 0.3556 1.524)
			(layers "B.Cu" "B.Mask" "B.Paste")
			(net "PD_SMB_M2_EN")
		)
		(pad "6" smd rect
			(at -0.32512 -2.05486 180)
			(size 0.3556 1.524)
			(layers "B.Cu" "B.Mask" "B.Paste")
			(net "Net_6506")
		)
		(pad "7" smd rect
			(at 0.32512 -2.05486 180)
			(size 0.3556 1.524)
			(layers "B.Cu" "B.Mask" "B.Paste")
			(net "IRQ_MEZZ_LAN_ALERT_N")
		)
		(pad "8" smd rect
			(at 0.97536 -2.05486 180)
			(size 0.3556 1.524)
			(layers "B.Cu" "B.Mask" "B.Paste")
			(net "P3V3_STBY")
		)
	)
	(footprint ""
		(layer "B.Cu")
		(at 26.896568 -154.559 180)
		(property "Reference" "C9L3"
			(at 0 0 0)
			(layer "B.SilkS")
			(hide yes)
			(effects
				(font
					(size 1.27 1.27)
				)
				(justify mirror)
			)
		)
		(property "Value" ""
			(at 0 0 0)
			(layer "B.Fab")
			(effects
				(font
					(size 1.27 1.27)
				)
				(justify mirror)
			)
		)
		(duplicate_pad_numbers_are_jumpers no)
		(fp_poly
			(pts
				(xy -0.3048 -0.1016) (xy -0.3048 0.9906) (xy 0.3048 0.9906) (xy 0.3048 -0.1016)
			)
			(stroke
				(width 0)
				(type default)
			)
			(fill no)
			(layer "B.CrtYd")
		)
		(fp_line
			(start 0.3048 0.9906)
			(end -0.3048 0.9906)
			(stroke
				(width 0.1)
				(type default)
			)
			(layer "B.Fab")
		)
		(fp_line
			(start 0.3048 -0.1016)
			(end 0.3048 0.9906)
			(stroke
				(width 0.1)
				(type default)
			)
			(layer "B.Fab")
		)
		(fp_line
			(start -0.3048 0.9906)
			(end -0.3048 -0.1016)
			(stroke
				(width 0.1)
				(type default)
			)
			(layer "B.Fab")
		)
		(fp_line
			(start -0.3048 -0.1016)
			(end 0.3048 -0.1016)
			(stroke
				(width 0.1)
				(type default)
			)
			(layer "B.Fab")
		)
		(pad "1" smd rect
			(at 0 0)
			(size 0.508 0.508)
			(layers "B.Cu" "B.Mask" "B.Paste")
			(net "M_M_CPU_VREF")
		)
		(pad "2" smd rect
			(at 0 0.889)
			(size 0.508 0.508)
			(layers "B.Cu" "B.Mask" "B.Paste")
			(net "GND")
		)
		(zone
			(layer "B.Cu")
			(hatch none 0.5)
			(connect_pads
				(clearance 0)
			)
			(min_thickness 0.25)
			(keepout
				(tracks not_allowed)
				(vias allowed)
				(pads allowed)
				(copperpour not_allowed)
				(footprints allowed)
			)
			(placement
				(enabled no)
				(sheetname "")
			)
			(fill
				(thermal_gap 0.5)
				(thermal_bridge_width 0.5)
				(island_removal_mode 0)
			)
			(polygon
				(pts
					(xy 26.642568 -155.194) (xy 27.150568 -155.194) (xy 27.150568 -154.813) (xy 26.642568 -154.813)
				)
			)
		)
		(zone
			(layer "B.Cu")
			(hatch none 0.5)
			(connect_pads
				(clearance 0)
			)
			(min_thickness 0.25)
			(keepout
				(tracks allowed)
				(vias not_allowed)
				(pads allowed)
				(copperpour not_allowed)
				(footprints allowed)
			)
			(placement
				(enabled no)
				(sheetname "")
			)
			(fill
				(thermal_gap 0.5)
				(thermal_bridge_width 0.5)
				(island_removal_mode 0)
			)
			(polygon
				(pts
					(xy 26.642568 -154.813) (xy 27.150568 -154.813) (xy 27.150568 -155.194) (xy 26.642568 -155.194)
				)
			)
		)
	)
	(footprint ""
		(layer "B.Cu")
		(at 377.8758 -135.1788 -90)
		(property "Reference" "FB3M1"
			(at 0 0 90)
			(layer "B.SilkS")
			(hide yes)
			(effects
				(font
					(size 1.27 1.27)
				)
				(justify mirror)
			)
		)
		(property "Value" ""
			(at 0 0 90)
			(layer "B.Fab")
			(effects
				(font
					(size 1.27 1.27)
				)
				(justify mirror)
			)
		)
		(duplicate_pad_numbers_are_jumpers no)
		(fp_poly
			(pts
				(xy 0.15113 -0.47498) (xy -1.59893 -0.47498) (xy -1.59893 0.47498) (xy 0.15113 0.47498)
			)
			(stroke
				(width 0)
				(type default)
			)
			(fill no)
			(layer "B.CrtYd")
		)
		(fp_line
			(start -1.59893 0.47498)
			(end 0.15113 0.47498)
			(stroke
				(width 0.1)
				(type default)
			)
			(layer "B.Fab")
		)
		(fp_line
			(start 0.15113 0.47498)
			(end 0.15113 -0.47498)
			(stroke
				(width 0.1)
				(type default)
			)
			(layer "B.Fab")
		)
		(fp_line
			(start -1.59893 -0.47498)
			(end -1.59893 0.47498)
			(stroke
				(width 0.1)
				(type default)
			)
			(layer "B.Fab")
		)
		(fp_line
			(start 0.15113 -0.47498)
			(end -1.59893 -0.47498)
			(stroke
				(width 0.1)
				(type default)
			)
			(layer "B.Fab")
		)
		(pad "1" smd rect
			(at 0 0 90)
			(size 0.9398 0.9398)
			(layers "B.Cu" "B.Mask" "B.Paste")
			(net "P1V05_PCH_STBY")
		)
		(pad "2" smd rect
			(at -1.4478 0 90)
			(size 0.9398 0.9398)
			(layers "B.Cu" "B.Mask" "B.Paste")
			(net "P1V05_PCH_STBY_VCCA_PLL1")
		)
		(zone
			(layer "B.Cu")
			(hatch none 0.5)
			(connect_pads
				(clearance 0)
			)
			(min_thickness 0.25)
			(keepout
				(tracks not_allowed)
				(vias allowed)
				(pads allowed)
				(copperpour not_allowed)
				(footprints allowed)
			)
			(placement
				(enabled no)
				(sheetname "")
			)
			(fill
				(thermal_gap 0.5)
				(thermal_bridge_width 0.5)
				(island_removal_mode 0)
			)
			(polygon
				(pts
					(xy 377.4059 -135.6487) (xy 378.3457 -135.6487) (xy 378.3457 -136.1567) (xy 377.4059 -136.1567)
				)
			)
		)
		(zone
			(layer "B.Cu")
			(hatch none 0.5)
			(connect_pads
				(clearance 0)
			)
			(min_thickness 0.25)
			(keepout
				(tracks allowed)
				(vias not_allowed)
				(pads allowed)
				(copperpour not_allowed)
				(footprints allowed)
			)
			(placement
				(enabled no)
				(sheetname "")
			)
			(fill
				(thermal_gap 0.5)
				(thermal_bridge_width 0.5)
				(island_removal_mode 0)
			)
			(polygon
				(pts
					(xy 377.4059 -135.6487) (xy 378.3457 -135.6487) (xy 378.3457 -136.1567) (xy 377.4059 -136.1567)
				)
			)
		)
	)
	(footprint ""
		(layer "B.Cu")
		(at 425.203874 -40.931846 180)
		(property "Reference" "C25W59"
			(at -0.97536 0.76708 270)
			(unlocked yes)
			(layer "B.SilkS")
			(effects
				(font
					(size 0.4064 0.254)
					(thickness 0.1524)
				)
				(justify mirror)
			)
		)
		(property "Value" ""
			(at 0 0 0)
			(layer "B.Fab")
			(effects
				(font
					(size 1.27 1.27)
				)
				(justify mirror)
			)
		)
		(duplicate_pad_numbers_are_jumpers no)
		(fp_poly
			(pts
				(xy 0.4953 -0.2032) (xy -0.4953 -0.2032) (xy -0.4953 1.6002) (xy 0.4953 1.6002)
			)
			(stroke
				(width 0)
				(type default)
			)
			(fill no)
			(layer "B.CrtYd")
		)
		(fp_line
			(start 0.4953 1.6002)
			(end 0.4953 -0.2032)
			(stroke
				(width 0.1)
				(type default)
			)
			(layer "B.Fab")
		)
		(fp_line
			(start 0.4953 -0.2032)
			(end -0.4953 -0.2032)
			(stroke
				(width 0.1)
				(type default)
			)
			(layer "B.Fab")
		)
		(fp_line
			(start -0.4953 1.6002)
			(end 0.4953 1.6002)
			(stroke
				(width 0.1)
				(type default)
			)
			(layer "B.Fab")
		)
		(fp_line
			(start -0.4953 -0.2032)
			(end -0.4953 1.6002)
			(stroke
				(width 0.1)
				(type default)
			)
			(layer "B.Fab")
		)
		(pad "1" smd rect
			(at 0 0)
			(size 0.762 0.889)
			(layers "B.Cu" "B.Mask" "B.Paste")
			(net "VCC_PA_3V3")
		)
		(pad "2" smd rect
			(at 0 1.397)
			(size 0.762 0.889)
			(layers "B.Cu" "B.Mask" "B.Paste")
			(net "GND")
		)
		(zone
			(layer "B.Cu")
			(hatch none 0.5)
			(connect_pads
				(clearance 0)
			)
			(min_thickness 0.25)
			(keepout
				(tracks not_allowed)
				(vias allowed)
				(pads allowed)
				(copperpour not_allowed)
				(footprints allowed)
			)
			(placement
				(enabled no)
				(sheetname "")
			)
			(fill
				(thermal_gap 0.5)
				(thermal_bridge_width 0.5)
				(island_removal_mode 0)
			)
			(polygon
				(pts
					(xy 424.822874 -41.376346) (xy 425.584874 -41.376346) (xy 425.584874 -41.884346) (xy 424.822874 -41.884346)
				)
			)
		)
	)
	(footprint ""
		(layer "B.Cu")
		(at 244.5512 -125.55601 -90)
		(property "Reference" "C5M10"
			(at 0 0 90)
			(layer "B.SilkS")
			(hide yes)
			(effects
				(font
					(size 1.27 1.27)
				)
				(justify mirror)
			)
		)
		(property "Value" ""
			(at 0 0 90)
			(layer "B.Fab")
			(effects
				(font
					(size 1.27 1.27)
				)
				(justify mirror)
			)
		)
		(duplicate_pad_numbers_are_jumpers no)
		(fp_rect
			(start 0.500126 1.598422)
			(end -0.500126 -0.201422)
			(stroke
				(width 0)
				(type default)
			)
			(fill no)
			(layer "B.CrtYd")
		)
		(fp_line
			(start -0.500126 1.598422)
			(end 0.500126 1.598422)
			(stroke
				(width 0.1)
				(type default)
			)
			(layer "B.Fab")
		)
		(fp_line
			(start 0.500126 1.598422)
			(end 0.500126 -0.201422)
			(stroke
				(width 0.1)
				(type default)
			)
			(layer "B.Fab")
		)
		(fp_line
			(start -0.500126 -0.201422)
			(end -0.500126 1.598422)
			(stroke
				(width 0.1)
				(type default)
			)
			(layer "B.Fab")
		)
		(fp_line
			(start 0.500126 -0.201422)
			(end -0.500126 -0.201422)
			(stroke
				(width 0.1)
				(type default)
			)
			(layer "B.Fab")
		)
		(pad "1" smd rect
			(at 0 0 180)
			(size 0.889 0.9906)
			(layers "B.Cu" "B.Mask" "B.Paste")
			(net "PVDDQ_DEF")
		)
		(pad "2" smd rect
			(at 0 1.397 180)
			(size 0.889 0.9906)
			(layers "B.Cu" "B.Mask" "B.Paste")
			(net "GND")
		)
		(zone
			(layer "B.Cu")
			(hatch none 0.5)
			(connect_pads
				(clearance 0)
			)
			(min_thickness 0.25)
			(keepout
				(tracks allowed)
				(vias not_allowed)
				(pads allowed)
				(copperpour not_allowed)
				(footprints allowed)
			)
			(placement
				(enabled no)
				(sheetname "")
			)
			(fill
				(thermal_gap 0.5)
				(thermal_bridge_width 0.5)
				(island_removal_mode 0)
			)
			(polygon
				(pts
					(xy 243.5987 -125.06071) (xy 244.1067 -125.06071) (xy 244.1067 -126.05131) (xy 243.5987 -126.05131)
				)
			)
		)
		(zone
			(layer "B.Cu")
			(hatch none 0.5)
			(connect_pads
				(clearance 0)
			)
			(min_thickness 0.25)
			(keepout
				(tracks not_allowed)
				(vias allowed)
				(pads allowed)
				(copperpour not_allowed)
				(footprints allowed)
			)
			(placement
				(enabled no)
				(sheetname "")
			)
			(fill
				(thermal_gap 0.5)
				(thermal_bridge_width 0.5)
				(island_removal_mode 0)
			)
			(polygon
				(pts
					(xy 243.5987 -125.06071) (xy 244.1067 -125.06071) (xy 244.1067 -126.05131) (xy 243.5987 -126.05131)
				)
			)
		)
	)
)
